FILE_TYPE = CONNECTIVITY;
{Allegro Design Entry HDL 16.6-p007 (v16-6-112F) 10/10/2012}
"PAGE_NUMBER" = 124;
0"NC";
1"GND\g";
2"GND\g";
3"GND\g";
4"GND\g";
5"GND\g";
6"GND\g";
%"GND"
"1","(225,825)","0","mstr_symbols","I13";
;
HDL_POWER"GND"
BODY_TYPE"PLUMBING"
SIZE"1B"
CDS_LIB"mstr_symbols"
VOLTAGE"0.0V";
"A\NAC"1;
%"GND"
"1","(2200,4075)","0","mstr_symbols","I14";
;
HDL_POWER"GND"
BODY_TYPE"PLUMBING"
CDS_LIB"mstr_symbols"
SIZE"1B"
VOLTAGE"0.0V";
"A\NAC"2;
%"LBG_CORE_QAT_EXT_D"
"14","(1200,2700)","0","mstr_u_proc","I15";
;
CDS_SEC"14"
ROOM"SB"
CDS_LOCATION"U7C1"
BOM_COST"SB"
CDS_LIB"mstr_u_proc"
SEC"14"
SEC_TYPE"BGA1"
PACK_TYPE"BGA1"
MATERIAL"IC"
PART_NUMBER"H91415-002"
LOCATION"U7C1";
"VSS<74>"
$PN"BK24"1;
"VSS<73>"
$PN"BK27"1;
"VSS<72>"
$PN"BK31"1;
"VSS<71>"
$PN"BK35"1;
"VSS<70>"
$PN"BK38"1;
"VSS<69>"
$PN"BK42"1;
"VSS<68>"
$PN"BK50"1;
"VSS<67>"
$PN"BL22"1;
"VSS<66>"
$PN"BL40"1;
"VSS<65>"
$PN"BL68"1;
"VSS<64>"
$PN"BL37"1;
"VSS<63>"
$PN"BL5"1;
"VSS<62>"
$PN"BL63"1;
"VSS<61>"
$PN"BL70"1;
"VSS<60>"
$PN"BL72"1;
"VSS<59>"
$PN"BM13"1;
"VSS<58>"
$PN"BM17"1;
"VSS<57>"
$PN"BN37"1;
"VSS<56>"
$PN"BM46"1;
"VSS<55>"
$PN"BM50"1;
"VSS<54>"
$PN"BM58"1;
"VSS<53>"
$PN"BM69"1;
"VSS<52>"
$PN"BM71"1;
"VSS<51>"
$PN"BM9"1;
"VSS<50>"
$PN"BN22"1;
"VSS<49>"
$PN"BN59"1;
"VSS<48>"
$PN"BN5"1;
"VSS<47>"
$PN"BN52"1;
"VSS<46>"
$PN"BN66"1;
"VSS<45>"
$PN"BR20"1;
"VSS<44>"
$PN"BR50"1;
"VSS<43>"
$PN"BT8"1;
"VSS<42>"
$PN"BR54"1;
"VSS<41>"
$PN"BR58"1;
"VSS<40>"
$PN"BR6"1;
"VSS<39>"
$PN"BT66"1;
"VSS<38>"
$PN"BU13"1;
"VSS<37>"
$PN"BU11"1;
"VSS<36>"
$PN"BV49"1;
"VSS<35>"
$PN"BU15"1;
"VSS<34>"
$PN"BU18"1;
"VSS<33>"
$PN"BU20"1;
"VSS<32>"
$PN"BU22"1;
"VSS<31>"
$PN"BU24"1;
"VSS<30>"
$PN"BU26"1;
"VSS<29>"
$PN"BU28"1;
"VSS<28>"
$PN"BU30"1;
"VSS<27>"
$PN"BU32"1;
"VSS<26>"
$PN"BU34"1;
"VSS<25>"
$PN"BU37"1;
"VSS<24>"
$PN"BU39"1;
"VSS<23>"
$PN"BU41"1;
"VSS<22>"
$PN"BU43"1;
"VSS<21>"
$PN"BU45"1;
"VSS<20>"
$PN"BU48"1;
"VSS<19>"
$PN"BU50"1;
"VSS<18>"
$PN"BU52"1;
"VSS<17>"
$PN"BU54"1;
"VSS<16>"
$PN"BU57"1;
"VSS<15>"
$PN"BU59"1;
"VSS<14>"
$PN"BU61"1;
"VSS<13>"
$PN"BU63"1;
"VSS<12>"
$PN"BU9"1;
"VSS<11>"
$PN"BV40"1;
"VSS<10>"
$PN"BW15"1;
"VSS<9>"
$PN"BW18"1;
"VSS<8>"
$PN"BW26"1;
"VSS<7>"
$PN"BW52"1;
"VSS<6>"
$PN"BY40"1;
"VSS<5>"
$PN"BY49"1;
"VSS<4>"
$PN"CA15"2;
"VSS<3>"
$PN"CA18"2;
"VSS<2>"
$PN"CA26"2;
"VSS<1>"
$PN"CA50"2;
"VSS<0>"
$PN"CA52"2;
%"LBG_CORE_QAT_EXT_D"
"13","(-1475,2725)","0","mstr_u_proc","I16";
;
CDS_SEC"13"
ROOM"SB"
CDS_LOCATION"U7C1"
BOM_COST"SB"
CDS_LIB"mstr_u_proc"
SEC"13"
SEC_TYPE"BGA1"
PACK_TYPE"BGA1"
MATERIAL"IC"
PART_NUMBER"H91415-002"
LOCATION"U7C1";
"VSS<214>"
$PN"AL68"6;
"VSS<213>"
$PN"AL70"6;
"VSS<212>"
$PN"AL72"6;
"VSS<211>"
$PN"AM26"6;
"VSS<210>"
$PN"AM30"6;
"VSS<209>"
$PN"AM41"6;
"VSS<208>"
$PN"AM46"6;
"VSS<207>"
$PN"AN13"6;
"VSS<206>"
$PN"AN17"6;
"VSS<205>"
$PN"AN68"6;
"VSS<204>"
$PN"AP22"6;
"VSS<203>"
$PN"AN20"6;
"VSS<202>"
$PN"AN5"6;
"VSS<201>"
$PN"AN58"6;
"VSS<200>"
$PN"AN9"6;
"VSS<199>"
$PN"AP2"6;
"VSS<198>"
$PN"AP26"6;
"VSS<197>"
$PN"AP30"6;
"VSS<196>"
$PN"AP4"6;
"VSS<195>"
$PN"AP41"6;
"VSS<194>"
$PN"AP46"6;
"VSS<193>"
$PN"AP52"6;
"VSS<192>"
$PN"AP66"6;
"VSS<191>"
$PN"AR5"6;
"VSS<190>"
$PN"AR50"6;
"VSS<189>"
$PN"AR58"6;
"VSS<188>"
$PN"AR65"6;
"VSS<187>"
$PN"AR68"6;
"VSS<186>"
$PN"AR70"6;
"VSS<185>"
$PN"AR72"6;
"VSS<184>"
$PN"AT7"6;
"VSS<183>"
$PN"AT11"6;
"VSS<182>"
$PN"AT15"6;
"VSS<181>"
$PN"AT18"6;
"VSS<180>"
$PN"AT22"6;
"VSS<179>"
$PN"AT26"6;
"VSS<178>"
$PN"AT30"6;
"VSS<177>"
$PN"AT41"6;
"VSS<176>"
$PN"AT46"6;
"VSS<175>"
$PN"AT59"6;
"VSS<174>"
$PN"AU26"6;
"VSS<173>"
$PN"AU30"6;
"VSS<172>"
$PN"AE22"6;
"VSS<171>"
$PN"AU41"6;
"VSS<170>"
$PN"AU46"6;
"VSS<169>"
$PN"AU50"6;
"VSS<168>"
$PN"AU54"6;
"VSS<167>"
$PN"AU61"6;
"VSS<166>"
$PN"AV5"6;
"VSS<165>"
$PN"AV22"6;
"VSS<164>"
$PN"AV59"6;
"VSS<163>"
$PN"AV68"6;
"VSS<162>"
$PN"AW9"6;
"VSS<161>"
$PN"AW13"6;
"VSS<160>"
$PN"AW17"6;
"VSS<159>"
$PN"AW26"6;
"VSS<158>"
$PN"AW30"6;
"VSS<157>"
$PN"AW32"6;
"VSS<156>"
$PN"AW34"6;
"VSS<155>"
$PN"AW36"6;
"VSS<154>"
$PN"AW37"6;
"VSS<153>"
$PN"AW39"6;
"VSS<152>"
$PN"AW41"6;
"VSS<151>"
$PN"AW46"6;
"VSS<150>"
$PN"AW50"6;
"VSS<149>"
$PN"AW58"6;
"VSS<148>"
$PN"AW61"6;
"VSS<147>"
$PN"AY5"6;
"VSS<146>"
$PN"AY22"6;
"VSS<145>"
$PN"AY56"6;
"VSS<144>"
$PN"AY63"5;
"VSS<143>"
$PN"AY68"5;
"VSS<142>"
$PN"BA50"5;
"VSS<141>"
$PN"BA54"5;
"VSS<140>"
$PN"BA58"5;
"VSS<139>"
$PN"BB5"5;
"VSS<138>"
$PN"BB7"5;
"VSS<137>"
$PN"BB11"5;
"VSS<136>"
$PN"BB15"5;
"VSS<135>"
$PN"BB18"5;
"VSS<134>"
$PN"BB22"5;
"VSS<133>"
$PN"BB44"5;
"VSS<132>"
$PN"BB59"5;
"VSS<131>"
$PN"BB66"5;
"VSS<130>"
$PN"BB68"5;
"VSS<129>"
$PN"BB70"5;
"VSS<128>"
$PN"BB72"5;
"VSS<127>"
$PN"BC69"5;
"VSS<126>"
$PN"BC71"5;
"VSS<125>"
$PN"BD24"5;
"VSS<124>"
$PN"BD27"5;
"VSS<123>"
$PN"BD31"5;
"VSS<122>"
$PN"BD35"5;
"VSS<121>"
$PN"BD5"5;
"VSS<120>"
$PN"BD50"5;
"VSS<119>"
$PN"BD54"5;
"VSS<118>"
$PN"BD68"5;
"VSS<117>"
$PN"BE29"5;
"VSS<116>"
$PN"BE33"5;
"VSS<115>"
$PN"BE37"5;
"VSS<114>"
$PN"BE56"5;
"VSS<113>"
$PN"BE59"5;
"VSS<112>"
$PN"BE63"5;
"VSS<111>"
$PN"BE66"5;
"VSS<110>"
$PN"BF13"5;
"VSS<109>"
$PN"BF17"5;
"VSS<108>"
$PN"BF54"5;
"VSS<107>"
$PN"BG44"5;
"VSS<106>"
$PN"BF20"5;
"VSS<105>"
$PN"BF24"5;
"VSS<104>"
$PN"BF27"5;
"VSS<103>"
$PN"BF38"5;
"VSS<102>"
$PN"BF42"5;
"VSS<101>"
$PN"BF5"5;
"VSS<100>"
$PN"BF50"5;
"VSS<99>"
$PN"BF58"5;
"VSS<98>"
$PN"BF61"5;
"VSS<97>"
$PN"BF65"5;
"VSS<96>"
$PN"BF68"5;
"VSS<95>"
$PN"BF9"5;
"VSS<94>"
$PN"BG33"5;
"VSS<93>"
$PN"BG48"5;
"VSS<92>"
$PN"BG59"5;
"VSS<91>"
$PN"BG63"5;
"VSS<90>"
$PN"BH27"5;
"VSS<89>"
$PN"BH38"5;
"VSS<88>"
$PN"BH42"5;
"VSS<87>"
$PN"BH46"5;
"VSS<86>"
$PN"BH54"5;
"VSS<85>"
$PN"BJ1"5;
"VSS<84>"
$PN"BJ11"5;
"VSS<83>"
$PN"BJ5"5;
"VSS<82>"
$PN"BJ7"5;
"VSS<81>"
$PN"BJ15"5;
"VSS<80>"
$PN"BJ18"5;
"VSS<79>"
$PN"BJ26"5;
"VSS<78>"
$PN"BJ3"5;
"VSS<77>"
$PN"BJ33"5;
"VSS<76>"
$PN"BJ52"5;
"VSS<75>"
$PN"BJ68"5;
%"LBG_CORE_QAT_EXT_D"
"12","(-4000,2700)","0","mstr_u_proc","I17";
;
CDS_SEC"12"
ROOM"SB"
CDS_LOCATION"U7C1"
BOM_COST"SB"
CDS_LIB"mstr_u_proc"
SEC"12"
SEC_TYPE"BGA1"
PACK_TYPE"BGA1"
LOCATION"U7C1"
MATERIAL"IC"
PART_NUMBER"H91415-002";
"VSS<354>"
$PN"N35"4;
"VSS<353>"
$PN"N38"4;
"VSS<352>"
$PN"N46"4;
"VSS<351>"
$PN"N5"4;
"VSS<350>"
$PN"R38"4;
"VSS<349>"
$PN"N68"4;
"VSS<348>"
$PN"N9"4;
"VSS<347>"
$PN"AE43"4;
"VSS<346>"
$PN"P63"4;
"VSS<345>"
$PN"R27"4;
"VSS<344>"
$PN"U42"4;
"VSS<343>"
$PN"R5"4;
"VSS<342>"
$PN"R50"4;
"VSS<341>"
$PN"R54"4;
"VSS<340>"
$PN"T56"4;
"VSS<339>"
$PN"R58"4;
"VSS<338>"
$PN"R68"4;
"VSS<337>"
$PN"T11"4;
"VSS<336>"
$PN"T15"4;
"VSS<335>"
$PN"T18"4;
"VSS<334>"
$PN"T22"4;
"VSS<333>"
$PN"T26"4;
"VSS<332>"
$PN"T29"4;
"VSS<331>"
$PN"T33"4;
"VSS<330>"
$PN"T37"4;
"VSS<329>"
$PN"T40"4;
"VSS<328>"
$PN"AJ45"4;
"VSS<327>"
$PN"T48"4;
"VSS<326>"
$PN"T52"4;
"VSS<325>"
$PN"T66"4;
"VSS<324>"
$PN"T7"4;
"VSS<323>"
$PN"AF50"4;
"VSS<322>"
$PN"AG46"4;
"VSS<321>"
$PN"U58"4;
"VSS<320>"
$PN"V26"4;
"VSS<319>"
$PN"V48"4;
"VSS<318>"
$PN"V5"4;
"VSS<317>"
$PN"V52"4;
"VSS<316>"
$PN"W58"4;
"VSS<315>"
$PN"V66"4;
"VSS<314>"
$PN"V68"4;
"VSS<313>"
$PN"W13"4;
"VSS<312>"
$PN"W17"4;
"VSS<311>"
$PN"W20"4;
"VSS<310>"
$PN"W24"4;
"VSS<309>"
$PN"AA50"4;
"VSS<308>"
$PN"Y43"4;
"VSS<307>"
$PN"W61"4;
"VSS<306>"
$PN"W9"4;
"VSS<305>"
$PN"Y22"4;
"VSS<304>"
$PN"Y27"4;
"VSS<303>"
$PN"Y48"4;
"VSS<302>"
$PN"Y5"4;
"VSS<301>"
$PN"Y52"4;
"VSS<300>"
$PN"Y59"4;
"VSS<299>"
$PN"Y63"4;
"VSS<298>"
$PN"Y68"4;
"VSS<297>"
$PN"AA26"4;
"VSS<296>"
$PN"AA27"4;
"VSS<295>"
$PN"AA43"4;
"VSS<294>"
$PN"AA48"4;
"VSS<293>"
$PN"AB5"4;
"VSS<292>"
$PN"AB68"4;
"VSS<291>"
$PN"AB70"4;
"VSS<290>"
$PN"AB72"4;
"VSS<289>"
$PN"AC11"4;
"VSS<288>"
$PN"AC15"4;
"VSS<287>"
$PN"AC18"4;
"VSS<286>"
$PN"AC22"4;
"VSS<285>"
$PN"AC45"4;
"VSS<284>"
$PN"AD58"3;
"VSS<283>"
$PN"AC27"3;
"VSS<282>"
$PN"AC43"3;
"VSS<281>"
$PN"AC46"3;
"VSS<280>"
$PN"AC48"3;
"VSS<279>"
$PN"AC52"3;
"VSS<278>"
$PN"AC59"3;
"VSS<277>"
$PN"AC63"3;
"VSS<276>"
$PN"AC66"3;
"VSS<275>"
$PN"AC7"3;
"VSS<274>"
$PN"AD5"3;
"VSS<273>"
$PN"AD65"3;
"VSS<272>"
$PN"AD68"3;
"VSS<271>"
$PN"AE29"3;
"VSS<270>"
$PN"J18"3;
"VSS<269>"
$PN"AE48"3;
"VSS<268>"
$PN"AE52"3;
"VSS<267>"
$PN"AE56"3;
"VSS<266>"
$PN"AE59"3;
"VSS<265>"
$PN"AE63"3;
"VSS<264>"
$PN"AE66"3;
"VSS<263>"
$PN"AF1"3;
"VSS<262>"
$PN"AF13"3;
"VSS<261>"
$PN"AF5"3;
"VSS<260>"
$PN"AF9"3;
"VSS<259>"
$PN"AF17"3;
"VSS<258>"
$PN"AF24"3;
"VSS<257>"
$PN"AF3"3;
"VSS<256>"
$PN"AF68"3;
"VSS<255>"
$PN"AG26"3;
"VSS<254>"
$PN"AG30"3;
"VSS<253>"
$PN"AG41"3;
"VSS<252>"
$PN"AG43"3;
"VSS<251>"
$PN"AG52"3;
"VSS<250>"
$PN"AG56"3;
"VSS<249>"
$PN"AG59"3;
"VSS<248>"
$PN"AG66"3;
"VSS<247>"
$PN"AH20"3;
"VSS<246>"
$PN"AJ11"3;
"VSS<245>"
$PN"AJ32"3;
"VSS<244>"
$PN"AJ56"3;
"VSS<243>"
$PN"AK30"3;
"VSS<242>"
$PN"AJ15"3;
"VSS<241>"
$PN"AJ18"3;
"VSS<240>"
$PN"AJ22"3;
"VSS<239>"
$PN"AJ26"3;
"VSS<238>"
$PN"AJ30"3;
"VSS<237>"
$PN"AJ34"3;
"VSS<236>"
$PN"AJ36"3;
"VSS<235>"
$PN"AJ37"3;
"VSS<234>"
$PN"AJ39"3;
"VSS<233>"
$PN"AJ41"3;
"VSS<232>"
$PN"AJ5"3;
"VSS<231>"
$PN"AJ52"3;
"VSS<230>"
$PN"AJ59"3;
"VSS<229>"
$PN"AJ66"3;
"VSS<228>"
$PN"AJ68"3;
"VSS<227>"
$PN"AJ7"3;
"VSS<226>"
$PN"AK26"3;
"VSS<225>"
$PN"AK41"3;
"VSS<224>"
$PN"AK46"3;
"VSS<223>"
$PN"AK48"3;
"VSS<222>"
$PN"AK58"3;
"VSS<221>"
$PN"AK61"3;
"VSS<220>"
$PN"AK69"3;
"VSS<219>"
$PN"AK71"3;
"VSS<218>"
$PN"AL22"3;
"VSS<217>"
$PN"AL5"3;
"VSS<216>"
$PN"AL52"3;
"VSS<215>"
$PN"AL59"3;
%"GND"
"1","(-3125,600)","0","mstr_symbols","I4";
;
HDL_POWER"GND"
BODY_TYPE"PLUMBING"
CDS_LIB"mstr_symbols"
SIZE"1B"
VOLTAGE"0.0V";
"A\NAC"3;
%"GND"
"1","(-4950,600)","0","mstr_symbols","I6";
;
HDL_POWER"GND"
BODY_TYPE"PLUMBING"
CDS_LIB"mstr_symbols"
SIZE"1B"
VOLTAGE"0.0V";
"A\NAC"4;
%"GND"
"1","(-400,575)","0","mstr_symbols","I7";
;
HDL_POWER"GND"
BODY_TYPE"PLUMBING"
SIZE"1B"
CDS_LIB"mstr_symbols"
VOLTAGE"0.0V";
"A\NAC"5;
%"GND"
"1","(-2550,625)","0","mstr_symbols","I9";
;
HDL_POWER"GND"
BODY_TYPE"PLUMBING"
CDS_LIB"mstr_symbols"
SIZE"1B"
VOLTAGE"0.0V";
"A\NAC"6;
END.
